(kicad_pcb
	(version 20260206)
	(generator "pcbnew")
	(generator_version "10.0")
	(general
		(thickness 1.6)
		(legacy_teardrops no)
	)
	(paper "A4")
	(title_block
		(title "15969-1a.1015WZS0858.brd")
		(comment 1 "Tioga Pass / footprints 246-251 of 295")
	)
	(layers
		(0 "F.Cu" signal "TOP")
		(4 "In1.Cu" signal "L2GND")
		(6 "In2.Cu" signal "L3")
		(8 "In3.Cu" signal "L4")
		(10 "In4.Cu" signal "L5GND")
		(2 "B.Cu" signal "BOTTOM")
		(9 "F.Adhes" user "F.Adhesive")
		(11 "B.Adhes" user "B.Adhesive")
		(13 "F.Paste" user "Package Geometry/Pastemask Top")
		(15 "B.Paste" user "Package Geometry/Pastemask Bottom")
		(5 "F.SilkS" user "Ref Des/Silkscreen Top")
		(7 "B.SilkS" user "Ref Des/Silkscreen Bottom")
		(1 "F.Mask" user "Board Geometry/Soldermask Top")
		(3 "B.Mask" user "Board Geometry/Soldermask Bottom")
		(17 "Dwgs.User" user "User.Drawings")
		(19 "Cmts.User" user "User.Comments")
		(21 "Eco1.User" user "User.Eco1")
		(23 "Eco2.User" user "User.Eco2")
		(25 "Edge.Cuts" user "Board Geometry/Outline")
		(27 "Margin" user)
		(31 "F.CrtYd" user "Package Geometry/Place Bound Top")
		(29 "B.CrtYd" user "Package Geometry/Place Bound Bottom")
		(35 "F.Fab" user "Ref Des/Assembly Top")
		(33 "B.Fab" user "Ref Des/Assembly Bottom")
	)
	(footprint ""
		(layer "B.Cu")
		(at 46.150022 -20.100036 90)
		(property "Reference" "CN2"
			(at 0 0 90)
			(layer "B.SilkS")
			(hide yes)
			(effects
				(font
					(size 1.27 1.27)
				)
				(justify mirror)
			)
		)
		(property "Value" "ALP-CONN4F-GP"
			(at 6.7691 0.381 90)
			(unlocked yes)
			(layer "B.Fab")
			(hide yes)
			(effects
				(font
					(size 1.016 1.016)
					(thickness 0.1524)
				)
				(justify mirror)
			)
		)
		(property "Device Type" "C23118-P04C0-L"
			(at 6.7691 -1.143 90)
			(unlocked yes)
			(layer "B.Fab")
			(hide yes)
			(effects
				(font
					(size 1.016 1.016)
					(thickness 0.1524)
				)
				(justify mirror)
			)
		)
		(duplicate_pad_numbers_are_jumpers no)
		(fp_line
			(start 3.6322 -4.2926)
			(end -3.6322 -4.2926)
			(stroke
				(width 0.1524)
				(type default)
			)
			(layer "B.SilkS")
		)
		(fp_line
			(start -3.6322 -4.2926)
			(end -3.6322 3.6068)
			(stroke
				(width 0.1524)
				(type default)
			)
			(layer "B.SilkS")
		)
		(fp_line
			(start -5.5499 3.5179)
			(end -5.5499 17.0053)
			(stroke
				(width 0.3302)
				(type default)
			)
			(layer "B.SilkS")
		)
		(fp_line
			(start 5.0546 3.6068)
			(end 3.6322 3.6068)
			(stroke
				(width 0.1524)
				(type default)
			)
			(layer "B.SilkS")
		)
		(fp_line
			(start 3.6322 3.6068)
			(end 3.6322 -4.2926)
			(stroke
				(width 0.1524)
				(type default)
			)
			(layer "B.SilkS")
		)
		(fp_line
			(start -3.6322 3.6068)
			(end -5.461 3.6068)
			(stroke
				(width 0.1524)
				(type default)
			)
			(layer "B.SilkS")
		)
		(fp_line
			(start -5.461 3.6068)
			(end -5.461 16.9164)
			(stroke
				(width 0.1524)
				(type default)
			)
			(layer "B.SilkS")
		)
		(fp_line
			(start 1.016 15.9004)
			(end -1.016 15.9004)
			(stroke
				(width 0.1524)
				(type default)
			)
			(layer "B.SilkS")
		)
		(fp_line
			(start -1.016 15.9004)
			(end -1.016 16.9164)
			(stroke
				(width 0.1524)
				(type default)
			)
			(layer "B.SilkS")
		)
		(fp_line
			(start 5.0546 16.9164)
			(end 5.0546 3.6068)
			(stroke
				(width 0.1524)
				(type default)
			)
			(layer "B.SilkS")
		)
		(fp_line
			(start 1.016 16.9164)
			(end 1.016 15.9004)
			(stroke
				(width 0.1524)
				(type default)
			)
			(layer "B.SilkS")
		)
		(fp_line
			(start -5.461 16.9164)
			(end 5.0546 16.9164)
			(stroke
				(width 0.1524)
				(type default)
			)
			(layer "B.SilkS")
		)
		(fp_circle
			(center 2.100072 -2.750058)
			(end 2.100072 -1.111758)
			(stroke
				(width 0.3048)
				(type default)
			)
			(fill no)
			(layer "B.SilkS")
		)
		(fp_circle
			(center -2.100072 -2.750058)
			(end -2.100072 -1.111758)
			(stroke
				(width 0.3048)
				(type default)
			)
			(fill no)
			(layer "B.SilkS")
		)
		(fp_circle
			(center 2.100072 2.750058)
			(end 2.100072 4.388358)
			(stroke
				(width 0.3048)
				(type default)
			)
			(fill no)
			(layer "B.SilkS")
		)
		(fp_circle
			(center -2.100072 2.750058)
			(end -2.100072 4.388358)
			(stroke
				(width 0.3048)
				(type default)
			)
			(fill no)
			(layer "B.SilkS")
		)
		(fp_poly
			(pts
				(xy 2.667 -3.2512) (xy -2.667 -3.2512) (xy -2.667 3.8608) (xy -5.207 3.8608) (xy -5.207 16.6624)
				(xy 4.8006 16.6624) (xy 4.8006 3.8608) (xy 2.667 3.8608)
			)
			(stroke
				(width 0)
				(type default)
			)
			(fill no)
			(layer "B.CrtYd")
		)
		(fp_poly
			(pts
				(xy 5.3086 17.1704) (xy 5.3086 3.3528) (xy 3.8862 3.3528) (xy 3.8862 -4.5466) (xy -3.8862 -4.5466)
				(xy -3.8862 -0.00635) (xy -2.667 -0.00635) (xy -2.667 -3.2512) (xy 2.667 -3.2512) (xy 2.667 3.8608)
				(xy 4.8006 3.8608) (xy 4.8006 16.6624) (xy -5.207 16.6624) (xy -5.207 3.8608) (xy -2.667 3.8608)
				(xy -2.667 0.00635) (xy -3.8862 0.00635) (xy -3.8862 3.3528) (xy -5.715 3.3528) (xy -5.715 17.1704)
			)
			(stroke
				(width 0)
				(type default)
			)
			(fill no)
			(layer "B.CrtYd")
		)
		(fp_poly
			(pts
				(xy 5.3086 17.1704) (xy 5.3086 3.3528) (xy 3.8862 3.3528) (xy 3.8862 -4.5466) (xy -3.8862 -4.5466)
				(xy -3.8862 3.3528) (xy -5.715 3.3528) (xy -5.715 17.1704)
			)
			(stroke
				(width 0)
				(type default)
			)
			(fill no)
			(layer "B.Fab")
		)
		(pad "1" thru_hole circle
			(at -2.100072 2.750058 270)
			(size 2.5654 2.5654)
			(drill 1.8034)
			(layers "*.Cu" "*.Mask")
			(remove_unused_layers no)
			(net "GND")
			(clearance 0.127)
			(thermal_gap 0.127)
		)
		(pad "2" thru_hole circle
			(at 2.100072 2.750058 270)
			(size 2.5654 2.5654)
			(drill 1.8034)
			(layers "*.Cu" "*.Mask")
			(remove_unused_layers no)
			(net "GND")
			(clearance 0.127)
			(thermal_gap 0.127)
		)
		(pad "3" thru_hole circle
			(at -2.100072 -2.750058 270)
			(size 2.5654 2.5654)
			(drill 1.8034)
			(layers "*.Cu" "*.Mask")
			(remove_unused_layers no)
			(net "P12V_ATX")
			(clearance 0.127)
			(thermal_gap 0.127)
		)
		(pad "4" thru_hole circle
			(at 2.100072 -2.750058 270)
			(size 2.5654 2.5654)
			(drill 1.8034)
			(layers "*.Cu" "*.Mask")
			(remove_unused_layers no)
			(net "P12V_ATX")
			(clearance 0.127)
			(thermal_gap 0.127)
		)
	)
	(footprint ""
		(layer "B.Cu")
		(at 129.2352 -22.4028)
		(property "Reference" "R175"
			(at 0 0 0)
			(layer "B.SilkS")
			(hide yes)
			(effects
				(font
					(size 1.27 1.27)
				)
				(justify mirror)
			)
		)
		(property "Value" "0R2F-1-GP"
			(at -0.064008 -3.993896 0)
			(unlocked yes)
			(layer "B.Fab")
			(hide yes)
			(effects
				(font
					(size 1.016 1.016)
					(thickness 0.1524)
				)
				(justify mirror)
			)
		)
		(property "Device Type" "R402H16"
			(at -0.064008 -5.517896 0)
			(unlocked yes)
			(layer "B.Fab")
			(hide yes)
			(effects
				(font
					(size 1.016 1.016)
					(thickness 0.1524)
				)
				(justify mirror)
			)
		)
		(duplicate_pad_numbers_are_jumpers no)
		(fp_line
			(start -0.508 -0.9398)
			(end 0.508 -0.9398)
			(stroke
				(width 0.1524)
				(type default)
			)
			(layer "B.SilkS")
		)
		(fp_line
			(start 0.508 -0.9398)
			(end 0.508 0.9398)
			(stroke
				(width 0.1524)
				(type default)
			)
			(layer "B.SilkS")
		)
		(fp_rect
			(start 0.508 0.9398)
			(end -0.508 -0.9398)
			(stroke
				(width 0)
				(type default)
			)
			(fill no)
			(layer "B.CrtYd")
		)
		(fp_rect
			(start 0.508 0.9398)
			(end -0.508 -0.9398)
			(stroke
				(width 0)
				(type default)
			)
			(fill no)
			(layer "B.Fab")
		)
		(pad "1" smd custom
			(at 0 -0.4445 180)
			(size 0.1397 0.1397)
			(layers "B.Cu" "B.Mask" "B.Paste")
			(net "SMDAT_USB_HUB")
			(options
				(clearance outline)
				(anchor circle)
			)
			(primitives
				(gr_poly
					(pts
						(arc
							(start -0.1778 0.2794)
							(mid -0.249642 0.249642)
							(end -0.2794 0.1778)
						)
						(arc
							(start -0.2794 -0.1778)
							(mid -0.249642 -0.249642)
							(end -0.1778 -0.2794)
						)
						(arc
							(start 0.1778 -0.2794)
							(mid 0.249642 -0.249642)
							(end 0.2794 -0.1778)
						)
						(arc
							(start 0.2794 0.1778)
							(mid 0.249642 0.249642)
							(end 0.1778 0.2794)
						)
					)
					(width 0)
					(fill yes)
				)
			)
		)
		(pad "2" smd custom
			(at 0 0.4445 180)
			(size 0.1397 0.1397)
			(layers "B.Cu" "B.Mask" "B.Paste")
			(net "SMDAT_BMC_DEVICE")
			(options
				(clearance outline)
				(anchor circle)
			)
			(primitives
				(gr_poly
					(pts
						(arc
							(start -0.1778 0.2794)
							(mid -0.249642 0.249642)
							(end -0.2794 0.1778)
						)
						(arc
							(start -0.2794 -0.1778)
							(mid -0.249642 -0.249642)
							(end -0.1778 -0.2794)
						)
						(arc
							(start 0.1778 -0.2794)
							(mid 0.249642 -0.249642)
							(end 0.2794 -0.1778)
						)
						(arc
							(start 0.2794 0.1778)
							(mid 0.249642 0.249642)
							(end 0.1778 0.2794)
						)
					)
					(width 0)
					(fill yes)
				)
			)
		)
	)
	(footprint ""
		(layer "B.Cu")
		(at 19.2278 -31.9532 180)
		(property "Reference" "C90"
			(at 0 0 0)
			(layer "B.SilkS")
			(hide yes)
			(effects
				(font
					(size 1.27 1.27)
				)
				(justify mirror)
			)
		)
		(property "Value" "SC22U16V5MX-4-GP"
			(at 0.0762 -6.1214 180)
			(unlocked yes)
			(layer "B.Fab")
			(hide yes)
			(effects
				(font
					(size 1.016 1.016)
					(thickness 0.1524)
				)
				(justify mirror)
			)
		)
		(property "Device Type" "C805H58"
			(at 0.0762 -8.1534 180)
			(unlocked yes)
			(layer "B.Fab")
			(hide yes)
			(effects
				(font
					(size 1.016 1.016)
					(thickness 0.1524)
				)
				(justify mirror)
			)
		)
		(duplicate_pad_numbers_are_jumpers no)
		(fp_line
			(start -0.635 0)
			(end 0.635 0)
			(stroke
				(width 0.508)
				(type default)
			)
			(layer "B.SilkS")
		)
		(fp_rect
			(start 0.9652 1.778)
			(end -0.9652 -1.778)
			(stroke
				(width 0)
				(type default)
			)
			(fill no)
			(layer "B.CrtYd")
		)
		(fp_poly
			(pts
				(xy 0.9652 -1.778) (xy -0.9652 -1.778) (xy -0.9652 1.778) (xy 0.9652 1.778)
			)
			(stroke
				(width 0)
				(type default)
			)
			(fill no)
			(layer "B.Fab")
		)
		(pad "1" smd rect
			(at 0 -0.9652)
			(size 1.397 1.143)
			(layers "B.Cu" "B.Mask" "B.Paste")
			(net "P12V_ATX")
		)
		(pad "2" smd rect
			(at 0 0.9652)
			(size 1.397 1.143)
			(layers "B.Cu" "B.Mask" "B.Paste")
			(net "GND")
		)
	)
	(footprint ""
		(layer "B.Cu")
		(at 17.6657 -13.8557 180)
		(property "Reference" "PR9"
			(at 0 0 0)
			(layer "B.SilkS")
			(hide yes)
			(effects
				(font
					(size 1.27 1.27)
				)
				(justify mirror)
			)
		)
		(property "Value" "3K74R2F-GP"
			(at -0.064008 -3.993896 180)
			(unlocked yes)
			(layer "B.Fab")
			(hide yes)
			(effects
				(font
					(size 1.016 1.016)
					(thickness 0.1524)
				)
				(justify mirror)
			)
		)
		(property "Device Type" "R402H16"
			(at -0.064008 -5.517896 180)
			(unlocked yes)
			(layer "B.Fab")
			(hide yes)
			(effects
				(font
					(size 1.016 1.016)
					(thickness 0.1524)
				)
				(justify mirror)
			)
		)
		(duplicate_pad_numbers_are_jumpers no)
		(fp_line
			(start 0.508 -0.9398)
			(end 0.508 0.9398)
			(stroke
				(width 0.1524)
				(type default)
			)
			(layer "B.SilkS")
		)
		(fp_line
			(start -0.508 -0.9398)
			(end 0.508 -0.9398)
			(stroke
				(width 0.1524)
				(type default)
			)
			(layer "B.SilkS")
		)
		(fp_rect
			(start 0.508 0.9398)
			(end -0.508 -0.9398)
			(stroke
				(width 0)
				(type default)
			)
			(fill no)
			(layer "B.CrtYd")
		)
		(fp_rect
			(start 0.508 0.9398)
			(end -0.508 -0.9398)
			(stroke
				(width 0)
				(type default)
			)
			(fill no)
			(layer "B.Fab")
		)
		(pad "1" smd custom
			(at 0 -0.4445)
			(size 0.1397 0.1397)
			(layers "B.Cu" "B.Mask" "B.Paste")
			(net "P3V3_EN")
			(options
				(clearance outline)
				(anchor circle)
			)
			(primitives
				(gr_poly
					(pts
						(arc
							(start -0.1778 0.2794)
							(mid -0.249642 0.249642)
							(end -0.2794 0.1778)
						)
						(arc
							(start -0.2794 -0.1778)
							(mid -0.249642 -0.249642)
							(end -0.1778 -0.2794)
						)
						(arc
							(start 0.1778 -0.2794)
							(mid 0.249642 -0.249642)
							(end 0.2794 -0.1778)
						)
						(arc
							(start 0.2794 0.1778)
							(mid 0.249642 0.249642)
							(end 0.1778 0.2794)
						)
					)
					(width 0)
					(fill yes)
				)
			)
		)
		(pad "2" smd custom
			(at 0 0.4445)
			(size 0.1397 0.1397)
			(layers "B.Cu" "B.Mask" "B.Paste")
			(net "GND")
			(options
				(clearance outline)
				(anchor circle)
			)
			(primitives
				(gr_poly
					(pts
						(arc
							(start -0.1778 0.2794)
							(mid -0.249642 0.249642)
							(end -0.2794 0.1778)
						)
						(arc
							(start -0.2794 -0.1778)
							(mid -0.249642 -0.249642)
							(end -0.1778 -0.2794)
						)
						(arc
							(start 0.1778 -0.2794)
							(mid 0.249642 -0.249642)
							(end 0.2794 -0.1778)
						)
						(arc
							(start 0.2794 0.1778)
							(mid 0.249642 0.249642)
							(end 0.1778 0.2794)
						)
					)
					(width 0)
					(fill yes)
				)
			)
		)
	)
	(footprint ""
		(layer "B.Cu")
		(at 129.7432 -28.194 -90)
		(property "Reference" "LU1"
			(at 0 0 90)
			(layer "B.SilkS")
			(hide yes)
			(effects
				(font
					(size 1.27 1.27)
				)
				(justify mirror)
			)
		)
		(property "Value" "MMZ1608S301AT-GP"
			(at 0.0254 -2.8956 270)
			(unlocked yes)
			(layer "B.Fab")
			(hide yes)
			(effects
				(font
					(size 1.016 1.016)
					(thickness 0.1524)
				)
				(justify mirror)
			)
		)
		(property "Device Type" "L1608-UH38"
			(at 0.0254 -4.4196 270)
			(unlocked yes)
			(layer "B.Fab")
			(hide yes)
			(effects
				(font
					(size 1.016 1.016)
					(thickness 0.1524)
				)
				(justify mirror)
			)
		)
		(duplicate_pad_numbers_are_jumpers no)
		(fp_line
			(start -0.254 0)
			(end 0.254 0)
			(stroke
				(width 0.2032)
				(type default)
			)
			(layer "B.SilkS")
		)
		(fp_rect
			(start 0.5842 1.3335)
			(end -0.5842 -1.3335)
			(stroke
				(width 0)
				(type default)
			)
			(fill no)
			(layer "B.CrtYd")
		)
		(fp_rect
			(start 0.5842 1.3335)
			(end -0.5842 -1.3335)
			(stroke
				(width 0)
				(type default)
			)
			(fill no)
			(layer "B.Fab")
		)
		(pad "1" smd custom
			(at 0 -0.762 90)
			(size 0.2159 0.2159)
			(layers "B.Cu" "B.Mask" "B.Paste")
			(net "P3V3_STBY")
			(options
				(clearance outline)
				(anchor circle)
			)
			(primitives
				(gr_poly
					(pts
						(arc
							(start -0.3302 0.4318)
							(mid -0.402042 0.402042)
							(end -0.4318 0.3302)
						)
						(arc
							(start -0.4318 -0.3302)
							(mid -0.402042 -0.402042)
							(end -0.3302 -0.4318)
						)
						(arc
							(start 0.3302 -0.4318)
							(mid 0.402042 -0.402042)
							(end 0.4318 -0.3302)
						)
						(arc
							(start 0.4318 0.3302)
							(mid 0.402042 0.402042)
							(end 0.3302 0.4318)
						)
					)
					(width 0)
					(fill yes)
				)
			)
		)
		(pad "2" smd custom
			(at 0 0.762 90)
			(size 0.2159 0.2159)
			(layers "B.Cu" "B.Mask" "B.Paste")
			(net "P3V3_USB_HUB")
			(options
				(clearance outline)
				(anchor circle)
			)
			(primitives
				(gr_poly
					(pts
						(arc
							(start -0.3302 0.4318)
							(mid -0.402042 0.402042)
							(end -0.4318 0.3302)
						)
						(arc
							(start -0.4318 -0.3302)
							(mid -0.402042 -0.402042)
							(end -0.3302 -0.4318)
						)
						(arc
							(start 0.3302 -0.4318)
							(mid 0.402042 -0.402042)
							(end 0.4318 -0.3302)
						)
						(arc
							(start 0.4318 0.3302)
							(mid 0.402042 0.402042)
							(end 0.3302 0.4318)
						)
					)
					(width 0)
					(fill yes)
				)
			)
		)
	)
	(footprint ""
		(layer "B.Cu")
		(at 27.9527 -2.0066 180)
		(property "Reference" "PC6"
			(at 0 0 0)
			(layer "B.SilkS")
			(hide yes)
			(effects
				(font
					(size 1.27 1.27)
				)
				(justify mirror)
			)
		)
		(property "Value" "SC22U6D3V5MX-5-GP"
			(at 0.0762 -6.1214 180)
			(unlocked yes)
			(layer "B.Fab")
			(hide yes)
			(effects
				(font
					(size 1.016 1.016)
					(thickness 0.1524)
				)
				(justify mirror)
			)
		)
		(property "Device Type" "C805H56"
			(at 0.0762 -8.1534 180)
			(unlocked yes)
			(layer "B.Fab")
			(hide yes)
			(effects
				(font
					(size 1.016 1.016)
					(thickness 0.1524)
				)
				(justify mirror)
			)
		)
		(duplicate_pad_numbers_are_jumpers no)
		(fp_line
			(start -0.635 0)
			(end 0.635 0)
			(stroke
				(width 0.508)
				(type default)
			)
			(layer "B.SilkS")
		)
		(fp_rect
			(start 0.9652 1.778)
			(end -0.9652 -1.778)
			(stroke
				(width 0)
				(type default)
			)
			(fill no)
			(layer "B.CrtYd")
		)
		(fp_poly
			(pts
				(xy 0.9652 -1.778) (xy -0.9652 -1.778) (xy -0.9652 1.778) (xy 0.9652 1.778)
			)
			(stroke
				(width 0)
				(type default)
			)
			(fill no)
			(layer "B.Fab")
		)
		(pad "1" smd rect
			(at 0 -0.9652)
			(size 1.397 1.143)
			(layers "B.Cu" "B.Mask" "B.Paste")
			(net "P3V3_VR")
		)
		(pad "2" smd rect
			(at 0 0.9652)
			(size 1.397 1.143)
			(layers "B.Cu" "B.Mask" "B.Paste")
			(net "GND")
		)
	)
)
